# S9S_MB_2U (Grand Teton) — schematic netlist excerpt (pin names and nets, part order shuffled) for the footprints in the layout excerpt that follows; sources: Cadence DE-HDL packaged netlist, KiCad conversion of 03242023_DA0F0TMBIJ0_F0T_Motherboard_J_brd_V01_OCP.brd

C740  Q_CAP_DIFFBUS  DIFF BUS_0.22UF 6.3V 20% X6S  pkg C0201  page 176 : \1\ = P5E_CPU1_PE0_TX_C_DN<0> ; \2\ = P5E_CPU1_PE0_TX_DN<0>
R2474  Q_RES  0 5% EMPTY  pkg 0402LF  page 154 : A = FM_NCSI_OCP_V3_1_R_OE ; B = FB_BMC_ISOLATE
C2384  Q_CAP  100NF 50V 10% EMPTY  pkg C0402  page 307 : A = P12V_AUX ; B = GND

(kicad_pcb
	(version 20260206)
	(generator "pcbnew")
	(generator_version "10.0")
	(general
		(thickness 1.6)
		(legacy_teardrops no)
	)
	(paper "A4")
	(title_block
		(title "03242023_DA0F0TMBIJ0_F0T_Motherboard_J_brd_V01_OCP.brd")
		(comment 1 "Grand Teton / footprints 3107-3109 of 6105")
	)
	(layers
		(0 "F.Cu" signal "TOP")
		(4 "In1.Cu" signal "GND")
		(6 "In2.Cu" signal "IN1")
		(8 "In3.Cu" signal "GND1")
		(10 "In4.Cu" signal "IN2")
		(12 "In5.Cu" signal "GND2")
		(14 "In6.Cu" signal "IN3")
		(16 "In7.Cu" signal "GND3")
		(18 "In8.Cu" signal "VCC")
		(20 "In9.Cu" signal "VCC1")
		(22 "In10.Cu" signal "GND4")
		(24 "In11.Cu" signal "IN4")
		(26 "In12.Cu" signal "GND5")
		(28 "In13.Cu" signal "IN5")
		(30 "In14.Cu" signal "GND6")
		(32 "In15.Cu" signal "IN6")
		(34 "In16.Cu" signal "GND7")
		(2 "B.Cu" signal "BOTTOM")
		(9 "F.Adhes" user "F.Adhesive")
		(11 "B.Adhes" user "B.Adhesive")
		(13 "F.Paste" user "Package Geometry/Pastemask Top")
		(15 "B.Paste" user "Package Geometry/Pastemask Bottom")
		(5 "F.SilkS" user "Ref Des/Silkscreen Top")
		(7 "B.SilkS" user "Ref Des/Silkscreen Bottom")
		(1 "F.Mask" user "Board Geometry/Soldermask Top")
		(3 "B.Mask" user "Board Geometry/Soldermask Bottom")
		(17 "Dwgs.User" user "User.Drawings")
		(19 "Cmts.User" user "User.Comments")
		(21 "Eco1.User" user "User.Eco1")
		(23 "Eco2.User" user "User.Eco2")
		(25 "Edge.Cuts" user "Board Geometry/Outline")
		(27 "Margin" user)
		(31 "F.CrtYd" user "Package Geometry/Place Bound Top")
		(29 "B.CrtYd" user "Package Geometry/Place Bound Bottom")
		(35 "F.Fab" user "Ref Des/Assembly Top")
		(33 "B.Fab" user "Ref Des/Assembly Bottom")
	)
	(footprint ""
		(layer "F.Cu")
		(at 463.465926 -96.406208)
		(property "Reference" "R2474"
			(at 0 0 0)
			(layer "F.SilkS")
			(hide yes)
			(effects
				(font
					(size 1.27 1.27)
				)
			)
		)
		(property "Value" ""
			(at 0 0 0)
			(layer "F.Fab")
			(effects
				(font
					(size 1.27 1.27)
				)
			)
		)
		(duplicate_pad_numbers_are_jumpers no)
		(fp_line
			(start -0.7874 -0.4064)
			(end 0.7874 -0.4064)
			(stroke
				(width 0.1524)
				(type default)
			)
			(layer "F.SilkS")
		)
		(fp_line
			(start -0.7874 0.4064)
			(end -0.7874 -0.4064)
			(stroke
				(width 0.1524)
				(type default)
			)
			(layer "F.SilkS")
		)
		(fp_line
			(start 0.7874 -0.4064)
			(end 0.7874 0.4064)
			(stroke
				(width 0.1524)
				(type default)
			)
			(layer "F.SilkS")
		)
		(fp_line
			(start 0.7874 0.4064)
			(end -0.7874 0.4064)
			(stroke
				(width 0.1524)
				(type default)
			)
			(layer "F.SilkS")
		)
		(fp_line
			(start -0.67945 -0.305054)
			(end -0.12065 -0.305054)
			(stroke
				(width 0.1)
				(type default)
			)
			(layer "F.Fab")
		)
		(fp_line
			(start -0.67945 0.3048)
			(end -0.67945 -0.305054)
			(stroke
				(width 0.1)
				(type default)
			)
			(layer "F.Fab")
		)
		(fp_line
			(start -0.12065 -0.305054)
			(end -0.12065 -0.2794)
			(stroke
				(width 0.1)
				(type default)
			)
			(layer "F.Fab")
		)
		(fp_line
			(start -0.12065 -0.2794)
			(end 0.12065 -0.2794)
			(stroke
				(width 0.1)
				(type default)
			)
			(layer "F.Fab")
		)
		(fp_line
			(start -0.12065 0.2794)
			(end -0.12065 0.3048)
			(stroke
				(width 0.1)
				(type default)
			)
			(layer "F.Fab")
		)
		(fp_line
			(start -0.12065 0.3048)
			(end -0.67945 0.3048)
			(stroke
				(width 0.1)
				(type default)
			)
			(layer "F.Fab")
		)
		(fp_line
			(start 0.120396 0.2794)
			(end -0.12065 0.2794)
			(stroke
				(width 0.1)
				(type default)
			)
			(layer "F.Fab")
		)
		(fp_line
			(start 0.120396 0.3048)
			(end 0.120396 0.2794)
			(stroke
				(width 0.1)
				(type default)
			)
			(layer "F.Fab")
		)
		(fp_line
			(start 0.12065 -0.3048)
			(end 0.67945 -0.3048)
			(stroke
				(width 0.1)
				(type default)
			)
			(layer "F.Fab")
		)
		(fp_line
			(start 0.12065 -0.2794)
			(end 0.12065 -0.3048)
			(stroke
				(width 0.1)
				(type default)
			)
			(layer "F.Fab")
		)
		(fp_line
			(start 0.67945 -0.3048)
			(end 0.67945 0.3048)
			(stroke
				(width 0.1)
				(type default)
			)
			(layer "F.Fab")
		)
		(fp_line
			(start 0.67945 0.3048)
			(end 0.120396 0.3048)
			(stroke
				(width 0.1)
				(type default)
			)
			(layer "F.Fab")
		)
		(pad "1" smd circle
			(at -0.40005 0)
			(size 0 0)
			(layers "F.Cu" "F.Mask" "F.Paste")
			(net "FM_NCSI_OCP_V3_1_R_OE")
		)
		(pad "2" smd circle
			(at 0.40005 0)
			(size 0 0)
			(layers "F.Cu" "F.Mask" "F.Paste")
			(net "FB_BMC_ISOLATE")
		)
	)
	(footprint ""
		(layer "F.Cu")
		(at 212.598 -113.4872)
		(property "Reference" "C2384"
			(at 0 0 0)
			(layer "F.SilkS")
			(hide yes)
			(effects
				(font
					(size 1.27 1.27)
				)
			)
		)
		(property "Value" ""
			(at 0 0 0)
			(layer "F.Fab")
			(effects
				(font
					(size 1.27 1.27)
				)
			)
		)
		(duplicate_pad_numbers_are_jumpers no)
		(fp_line
			(start -0.7874 -0.4064)
			(end 0.7874 -0.4064)
			(stroke
				(width 0.1524)
				(type default)
			)
			(layer "F.SilkS")
		)
		(fp_line
			(start -0.7874 0.4064)
			(end -0.7874 -0.4064)
			(stroke
				(width 0.1524)
				(type default)
			)
			(layer "F.SilkS")
		)
		(fp_line
			(start 0.7874 -0.4064)
			(end 0.7874 0.4064)
			(stroke
				(width 0.1524)
				(type default)
			)
			(layer "F.SilkS")
		)
		(fp_line
			(start 0.7874 0.4064)
			(end -0.7874 0.4064)
			(stroke
				(width 0.1524)
				(type default)
			)
			(layer "F.SilkS")
		)
		(fp_line
			(start -0.67945 -0.305054)
			(end -0.12065 -0.305054)
			(stroke
				(width 0.1)
				(type default)
			)
			(layer "F.Fab")
		)
		(fp_line
			(start -0.67945 0.3048)
			(end -0.67945 -0.305054)
			(stroke
				(width 0.1)
				(type default)
			)
			(layer "F.Fab")
		)
		(fp_line
			(start -0.12065 -0.305054)
			(end -0.12065 -0.2794)
			(stroke
				(width 0.1)
				(type default)
			)
			(layer "F.Fab")
		)
		(fp_line
			(start -0.12065 -0.2794)
			(end 0.12065 -0.2794)
			(stroke
				(width 0.1)
				(type default)
			)
			(layer "F.Fab")
		)
		(fp_line
			(start -0.12065 0.2794)
			(end -0.12065 0.3048)
			(stroke
				(width 0.1)
				(type default)
			)
			(layer "F.Fab")
		)
		(fp_line
			(start -0.12065 0.3048)
			(end -0.67945 0.3048)
			(stroke
				(width 0.1)
				(type default)
			)
			(layer "F.Fab")
		)
		(fp_line
			(start 0.120396 0.2794)
			(end -0.12065 0.2794)
			(stroke
				(width 0.1)
				(type default)
			)
			(layer "F.Fab")
		)
		(fp_line
			(start 0.120396 0.3048)
			(end 0.120396 0.2794)
			(stroke
				(width 0.1)
				(type default)
			)
			(layer "F.Fab")
		)
		(fp_line
			(start 0.12065 -0.3048)
			(end 0.67945 -0.3048)
			(stroke
				(width 0.1)
				(type default)
			)
			(layer "F.Fab")
		)
		(fp_line
			(start 0.12065 -0.2794)
			(end 0.12065 -0.3048)
			(stroke
				(width 0.1)
				(type default)
			)
			(layer "F.Fab")
		)
		(fp_line
			(start 0.67945 -0.3048)
			(end 0.67945 0.3048)
			(stroke
				(width 0.1)
				(type default)
			)
			(layer "F.Fab")
		)
		(fp_line
			(start 0.67945 0.3048)
			(end 0.120396 0.3048)
			(stroke
				(width 0.1)
				(type default)
			)
			(layer "F.Fab")
		)
		(pad "1" smd circle
			(at -0.40005 0)
			(size 0 0)
			(layers "F.Cu" "F.Mask" "F.Paste")
			(net "P12V_AUX")
		)
		(pad "2" smd circle
			(at 0.40005 0)
			(size 0 0)
			(layers "F.Cu" "F.Mask" "F.Paste")
			(net "GND")
		)
	)
	(footprint ""
		(layer "F.Cu")
		(at 93.903038 -402.371052 -90)
		(property "Reference" "C740"
			(at 0 0 270)
			(layer "F.SilkS")
			(hide yes)
			(effects
				(font
					(size 1.27 1.27)
				)
			)
		)
		(property "Value" ""
			(at 0 0 270)
			(layer "F.Fab")
			(effects
				(font
					(size 1.27 1.27)
				)
			)
		)
		(duplicate_pad_numbers_are_jumpers no)
		(fp_line
			(start -0.299974 0.150114)
			(end -0.299974 -0.150114)
			(stroke
				(width 0.1)
				(type default)
			)
			(layer "F.Fab")
		)
		(fp_line
			(start 0.299974 0.150114)
			(end -0.299974 0.150114)
			(stroke
				(width 0.1)
				(type default)
			)
			(layer "F.Fab")
		)
		(fp_line
			(start -0.299974 -0.150114)
			(end 0.299974 -0.150114)
			(stroke
				(width 0.1)
				(type default)
			)
			(layer "F.Fab")
		)
		(fp_line
			(start 0.299974 -0.150114)
			(end 0.299974 0.150114)
			(stroke
				(width 0.1)
				(type default)
			)
			(layer "F.Fab")
		)
		(pad "1" smd rect
			(at -0.2667 0 270)
			(size 0.3048 0.381)
			(layers "F.Cu" "F.Mask" "F.Paste")
			(net "P5E_CPU1_PE0_TX_C_DN<0>")
		)
		(pad "2" smd rect
			(at 0.2667 0 270)
			(size 0.3048 0.381)
			(layers "F.Cu" "F.Mask" "F.Paste")
			(net "P5E_CPU1_PE0_TX_DN<0>")
		)
	)
)
